(kicad_pcb
	(version 20260206)
	(generator "pcbnew")
	(generator_version "10.0")
	(general
		(thickness 1.6)
		(legacy_teardrops no)
	)
	(paper "A4")
	(title_block
		(title "03242023_DA0F0TMBIJ0_F0T_Motherboard_J_brd_V01_OCP.brd")
		(comment 1 "Grand Teton / footprints 4165-4171 of 6105")
	)
	(layers
		(0 "F.Cu" signal "TOP")
		(4 "In1.Cu" signal "GND")
		(6 "In2.Cu" signal "IN1")
		(8 "In3.Cu" signal "GND1")
		(10 "In4.Cu" signal "IN2")
		(12 "In5.Cu" signal "GND2")
		(14 "In6.Cu" signal "IN3")
		(16 "In7.Cu" signal "GND3")
		(18 "In8.Cu" signal "VCC")
		(20 "In9.Cu" signal "VCC1")
		(22 "In10.Cu" signal "GND4")
		(24 "In11.Cu" signal "IN4")
		(26 "In12.Cu" signal "GND5")
		(28 "In13.Cu" signal "IN5")
		(30 "In14.Cu" signal "GND6")
		(32 "In15.Cu" signal "IN6")
		(34 "In16.Cu" signal "GND7")
		(2 "B.Cu" signal "BOTTOM")
		(9 "F.Adhes" user "F.Adhesive")
		(11 "B.Adhes" user "B.Adhesive")
		(13 "F.Paste" user "Package Geometry/Pastemask Top")
		(15 "B.Paste" user "Package Geometry/Pastemask Bottom")
		(5 "F.SilkS" user "Ref Des/Silkscreen Top")
		(7 "B.SilkS" user "Ref Des/Silkscreen Bottom")
		(1 "F.Mask" user "Board Geometry/Soldermask Top")
		(3 "B.Mask" user "Board Geometry/Soldermask Bottom")
		(17 "Dwgs.User" user "User.Drawings")
		(19 "Cmts.User" user "User.Comments")
		(21 "Eco1.User" user "User.Eco1")
		(23 "Eco2.User" user "User.Eco2")
		(25 "Edge.Cuts" user "Board Geometry/Outline")
		(27 "Margin" user)
		(31 "F.CrtYd" user "Package Geometry/Place Bound Top")
		(29 "B.CrtYd" user "Package Geometry/Place Bound Bottom")
		(35 "F.Fab" user "Ref Des/Assembly Top")
		(33 "B.Fab" user "Ref Des/Assembly Bottom")
	)
	(footprint ""
		(layer "B.Cu")
		(at 348.929706 -324.873366 -90)
		(property "Reference" "PC311_P0_2"
			(at 0 0 90)
			(layer "B.SilkS")
			(hide yes)
			(effects
				(font
					(size 1.27 1.27)
				)
				(justify mirror)
			)
		)
		(property "Value" ""
			(at 0 0 90)
			(layer "B.Fab")
			(effects
				(font
					(size 1.27 1.27)
				)
				(justify mirror)
			)
		)
		(duplicate_pad_numbers_are_jumpers no)
		(fp_line
			(start -1.524 0.762)
			(end 1.524 0.762)
			(stroke
				(width 0.1524)
				(type default)
			)
			(layer "B.SilkS")
		)
		(fp_line
			(start 1.524 0.762)
			(end 1.524 -0.762)
			(stroke
				(width 0.1524)
				(type default)
			)
			(layer "B.SilkS")
		)
		(fp_line
			(start -1.524 -0.762)
			(end -1.524 0.762)
			(stroke
				(width 0.1524)
				(type default)
			)
			(layer "B.SilkS")
		)
		(fp_line
			(start 1.524 -0.762)
			(end -1.524 -0.762)
			(stroke
				(width 0.1524)
				(type default)
			)
			(layer "B.SilkS")
		)
		(fp_line
			(start -1.1049 0.724916)
			(end -1.1049 -0.724916)
			(stroke
				(width 0.1)
				(type default)
			)
			(layer "B.Fab")
		)
		(fp_line
			(start 1.1049 0.724916)
			(end -1.1049 0.724916)
			(stroke
				(width 0.1)
				(type default)
			)
			(layer "B.Fab")
		)
		(fp_line
			(start -1.1049 -0.724916)
			(end 1.1049 -0.724916)
			(stroke
				(width 0.1)
				(type default)
			)
			(layer "B.Fab")
		)
		(fp_line
			(start 1.1049 -0.724916)
			(end 1.1049 0.724916)
			(stroke
				(width 0.1)
				(type default)
			)
			(layer "B.Fab")
		)
		(pad "1" smd rect
			(at 0.889 0 270)
			(size 1.016 1.27)
			(layers "B.Cu" "B.Mask" "B.Paste")
			(net "PVCCIN_CPU0")
		)
		(pad "2" smd rect
			(at -0.889 0 270)
			(size 1.016 1.27)
			(layers "B.Cu" "B.Mask" "B.Paste")
			(net "GND")
		)
	)
	(footprint ""
		(layer "B.Cu")
		(at 181.755542 -115.375436)
		(property "Reference" "C1133"
			(at 0 0 0)
			(layer "B.SilkS")
			(hide yes)
			(effects
				(font
					(size 1.27 1.27)
				)
				(justify mirror)
			)
		)
		(property "Value" ""
			(at 0 0 0)
			(layer "B.Fab")
			(effects
				(font
					(size 1.27 1.27)
				)
				(justify mirror)
			)
		)
		(duplicate_pad_numbers_are_jumpers no)
		(fp_line
			(start -0.69215 -0.2921)
			(end -0.69215 0.2921)
			(stroke
				(width 0.1524)
				(type default)
			)
			(layer "B.SilkS")
		)
		(fp_line
			(start -0.69215 0.2921)
			(end 0.69215 0.2921)
			(stroke
				(width 0.1524)
				(type default)
			)
			(layer "B.SilkS")
		)
		(fp_line
			(start 0.69215 -0.2921)
			(end -0.69215 -0.2921)
			(stroke
				(width 0.1524)
				(type default)
			)
			(layer "B.SilkS")
		)
		(fp_line
			(start 0.69215 0.2921)
			(end 0.69215 -0.2921)
			(stroke
				(width 0.1524)
				(type default)
			)
			(layer "B.SilkS")
		)
		(fp_line
			(start -0.51435 -0.2794)
			(end -0.51435 0.2794)
			(stroke
				(width 0.1)
				(type default)
			)
			(layer "B.Fab")
		)
		(fp_line
			(start -0.51435 0.2794)
			(end 0.51435 0.2794)
			(stroke
				(width 0.1)
				(type default)
			)
			(layer "B.Fab")
		)
		(fp_line
			(start 0.51435 -0.2794)
			(end -0.51435 -0.2794)
			(stroke
				(width 0.1)
				(type default)
			)
			(layer "B.Fab")
		)
		(fp_line
			(start 0.51435 0.2794)
			(end 0.51435 -0.2794)
			(stroke
				(width 0.1)
				(type default)
			)
			(layer "B.Fab")
		)
		(pad "1" smd circle
			(at 0.40005 0 180)
			(size 0 0)
			(layers "B.Cu" "B.Mask" "B.Paste")
			(net "P3V3_AUX_FPGA_VCCIO2")
		)
		(pad "2" smd circle
			(at -0.40005 0 180)
			(size 0 0)
			(layers "B.Cu" "B.Mask" "B.Paste")
			(net "GND")
		)
		(zone
			(layer "B.Cu")
			(hatch none 0.5)
			(connect_pads
				(clearance 0)
			)
			(min_thickness 0.25)
			(keepout
				(tracks not_allowed)
				(vias allowed)
				(pads allowed)
				(copperpour not_allowed)
				(footprints allowed)
			)
			(placement
				(enabled no)
				(sheetname "")
			)
			(fill
				(thermal_gap 0.5)
				(thermal_bridge_width 0.5)
				(island_removal_mode 0)
			)
			(polygon
				(pts
					(xy 181.946042 -115.287806) (xy 181.854602 -115.22964) (xy 181.655212 -115.22964) (xy 181.565042 -115.287806)
					(xy 181.565042 -115.463066) (xy 181.655212 -115.521486) (xy 181.854602 -115.521486) (xy 181.946042 -115.46332)
				)
			)
		)
	)
	(footprint ""
		(layer "B.Cu")
		(at 310.843422 -316.328044 90)
		(property "Reference" "R940"
			(at 0 0 90)
			(layer "B.SilkS")
			(hide yes)
			(effects
				(font
					(size 1.27 1.27)
				)
				(justify mirror)
			)
		)
		(property "Value" ""
			(at 0 0 90)
			(layer "B.Fab")
			(effects
				(font
					(size 1.27 1.27)
				)
				(justify mirror)
			)
		)
		(duplicate_pad_numbers_are_jumpers no)
		(fp_line
			(start 0.7874 -0.4064)
			(end -0.7874 -0.4064)
			(stroke
				(width 0.1524)
				(type default)
			)
			(layer "B.SilkS")
		)
		(fp_line
			(start -0.7874 -0.4064)
			(end -0.7874 0.4064)
			(stroke
				(width 0.1524)
				(type default)
			)
			(layer "B.SilkS")
		)
		(fp_line
			(start 0.7874 0.4064)
			(end 0.7874 -0.4064)
			(stroke
				(width 0.1524)
				(type default)
			)
			(layer "B.SilkS")
		)
		(fp_line
			(start -0.7874 0.4064)
			(end 0.7874 0.4064)
			(stroke
				(width 0.1524)
				(type default)
			)
			(layer "B.SilkS")
		)
		(fp_line
			(start 0.67945 -0.305054)
			(end 0.12065 -0.305054)
			(stroke
				(width 0.1)
				(type default)
			)
			(layer "B.Fab")
		)
		(fp_line
			(start 0.12065 -0.305054)
			(end 0.12065 -0.2794)
			(stroke
				(width 0.1)
				(type default)
			)
			(layer "B.Fab")
		)
		(fp_line
			(start -0.12065 -0.3048)
			(end -0.67945 -0.3048)
			(stroke
				(width 0.1)
				(type default)
			)
			(layer "B.Fab")
		)
		(fp_line
			(start -0.67945 -0.3048)
			(end -0.67945 0.3048)
			(stroke
				(width 0.1)
				(type default)
			)
			(layer "B.Fab")
		)
		(fp_line
			(start 0.12065 -0.2794)
			(end -0.12065 -0.2794)
			(stroke
				(width 0.1)
				(type default)
			)
			(layer "B.Fab")
		)
		(fp_line
			(start -0.12065 -0.2794)
			(end -0.12065 -0.3048)
			(stroke
				(width 0.1)
				(type default)
			)
			(layer "B.Fab")
		)
		(fp_line
			(start 0.12065 0.2794)
			(end 0.12065 0.3048)
			(stroke
				(width 0.1)
				(type default)
			)
			(layer "B.Fab")
		)
		(fp_line
			(start -0.120396 0.2794)
			(end 0.12065 0.2794)
			(stroke
				(width 0.1)
				(type default)
			)
			(layer "B.Fab")
		)
		(fp_line
			(start 0.67945 0.3048)
			(end 0.67945 -0.305054)
			(stroke
				(width 0.1)
				(type default)
			)
			(layer "B.Fab")
		)
		(fp_line
			(start 0.12065 0.3048)
			(end 0.67945 0.3048)
			(stroke
				(width 0.1)
				(type default)
			)
			(layer "B.Fab")
		)
		(fp_line
			(start -0.120396 0.3048)
			(end -0.120396 0.2794)
			(stroke
				(width 0.1)
				(type default)
			)
			(layer "B.Fab")
		)
		(fp_line
			(start -0.67945 0.3048)
			(end -0.120396 0.3048)
			(stroke
				(width 0.1)
				(type default)
			)
			(layer "B.Fab")
		)
		(pad "1" smd circle
			(at 0.40005 0 270)
			(size 0 0)
			(layers "B.Cu" "B.Mask" "B.Paste")
			(net "P3V3_AUX")
		)
		(pad "2" smd circle
			(at -0.40005 0 270)
			(size 0 0)
			(layers "B.Cu" "B.Mask" "B.Paste")
			(net "PWRGD_FAIL_CPU0_AB_R1")
		)
	)
	(footprint ""
		(layer "B.Cu")
		(at 192.052448 -400.609562 180)
		(property "Reference" "R3936"
			(at 0 0 0)
			(layer "B.SilkS")
			(hide yes)
			(effects
				(font
					(size 1.27 1.27)
				)
				(justify mirror)
			)
		)
		(property "Value" ""
			(at 0 0 0)
			(layer "B.Fab")
			(effects
				(font
					(size 1.27 1.27)
				)
				(justify mirror)
			)
		)
		(duplicate_pad_numbers_are_jumpers no)
		(fp_line
			(start 0.7874 0.4064)
			(end 0.7874 -0.4064)
			(stroke
				(width 0.1524)
				(type default)
			)
			(layer "B.SilkS")
		)
		(fp_line
			(start 0.7874 -0.4064)
			(end -0.7874 -0.4064)
			(stroke
				(width 0.1524)
				(type default)
			)
			(layer "B.SilkS")
		)
		(fp_line
			(start -0.7874 0.4064)
			(end 0.7874 0.4064)
			(stroke
				(width 0.1524)
				(type default)
			)
			(layer "B.SilkS")
		)
		(fp_line
			(start -0.7874 -0.4064)
			(end -0.7874 0.4064)
			(stroke
				(width 0.1524)
				(type default)
			)
			(layer "B.SilkS")
		)
		(fp_line
			(start 0.67945 0.3048)
			(end 0.67945 -0.305054)
			(stroke
				(width 0.1)
				(type default)
			)
			(layer "B.Fab")
		)
		(fp_line
			(start 0.67945 -0.305054)
			(end 0.12065 -0.305054)
			(stroke
				(width 0.1)
				(type default)
			)
			(layer "B.Fab")
		)
		(fp_line
			(start 0.12065 0.3048)
			(end 0.67945 0.3048)
			(stroke
				(width 0.1)
				(type default)
			)
			(layer "B.Fab")
		)
		(fp_line
			(start 0.12065 0.2794)
			(end 0.12065 0.3048)
			(stroke
				(width 0.1)
				(type default)
			)
			(layer "B.Fab")
		)
		(fp_line
			(start 0.12065 -0.2794)
			(end -0.12065 -0.2794)
			(stroke
				(width 0.1)
				(type default)
			)
			(layer "B.Fab")
		)
		(fp_line
			(start 0.12065 -0.305054)
			(end 0.12065 -0.2794)
			(stroke
				(width 0.1)
				(type default)
			)
			(layer "B.Fab")
		)
		(fp_line
			(start -0.120396 0.3048)
			(end -0.120396 0.2794)
			(stroke
				(width 0.1)
				(type default)
			)
			(layer "B.Fab")
		)
		(fp_line
			(start -0.120396 0.2794)
			(end 0.12065 0.2794)
			(stroke
				(width 0.1)
				(type default)
			)
			(layer "B.Fab")
		)
		(fp_line
			(start -0.12065 -0.2794)
			(end -0.12065 -0.3048)
			(stroke
				(width 0.1)
				(type default)
			)
			(layer "B.Fab")
		)
		(fp_line
			(start -0.12065 -0.3048)
			(end -0.67945 -0.3048)
			(stroke
				(width 0.1)
				(type default)
			)
			(layer "B.Fab")
		)
		(fp_line
			(start -0.67945 0.3048)
			(end -0.120396 0.3048)
			(stroke
				(width 0.1)
				(type default)
			)
			(layer "B.Fab")
		)
		(fp_line
			(start -0.67945 -0.3048)
			(end -0.67945 0.3048)
			(stroke
				(width 0.1)
				(type default)
			)
			(layer "B.Fab")
		)
		(pad "1" smd circle
			(at 0.40005 0)
			(size 0 0)
			(layers "B.Cu" "B.Mask" "B.Paste")
			(net "HSC_VDD")
		)
		(pad "2" smd circle
			(at -0.40005 0)
			(size 0 0)
			(layers "B.Cu" "B.Mask" "B.Paste")
			(net "HSC_D_OC")
		)
	)
	(footprint ""
		(layer "B.Cu")
		(at 404.002748 -59.939428 180)
		(property "Reference" "R773"
			(at 0 0 0)
			(layer "B.SilkS")
			(hide yes)
			(effects
				(font
					(size 1.27 1.27)
				)
				(justify mirror)
			)
		)
		(property "Value" ""
			(at 0 0 0)
			(layer "B.Fab")
			(effects
				(font
					(size 1.27 1.27)
				)
				(justify mirror)
			)
		)
		(duplicate_pad_numbers_are_jumpers no)
		(fp_line
			(start 0.7874 0.4064)
			(end 0.7874 -0.4064)
			(stroke
				(width 0.1524)
				(type default)
			)
			(layer "B.SilkS")
		)
		(fp_line
			(start 0.7874 -0.4064)
			(end -0.7874 -0.4064)
			(stroke
				(width 0.1524)
				(type default)
			)
			(layer "B.SilkS")
		)
		(fp_line
			(start -0.7874 0.4064)
			(end 0.7874 0.4064)
			(stroke
				(width 0.1524)
				(type default)
			)
			(layer "B.SilkS")
		)
		(fp_line
			(start -0.7874 -0.4064)
			(end -0.7874 0.4064)
			(stroke
				(width 0.1524)
				(type default)
			)
			(layer "B.SilkS")
		)
		(fp_line
			(start 0.67945 0.3048)
			(end 0.67945 -0.305054)
			(stroke
				(width 0.1)
				(type default)
			)
			(layer "B.Fab")
		)
		(fp_line
			(start 0.67945 -0.305054)
			(end 0.12065 -0.305054)
			(stroke
				(width 0.1)
				(type default)
			)
			(layer "B.Fab")
		)
		(fp_line
			(start 0.12065 0.3048)
			(end 0.67945 0.3048)
			(stroke
				(width 0.1)
				(type default)
			)
			(layer "B.Fab")
		)
		(fp_line
			(start 0.12065 0.2794)
			(end 0.12065 0.3048)
			(stroke
				(width 0.1)
				(type default)
			)
			(layer "B.Fab")
		)
		(fp_line
			(start 0.12065 -0.2794)
			(end -0.12065 -0.2794)
			(stroke
				(width 0.1)
				(type default)
			)
			(layer "B.Fab")
		)
		(fp_line
			(start 0.12065 -0.305054)
			(end 0.12065 -0.2794)
			(stroke
				(width 0.1)
				(type default)
			)
			(layer "B.Fab")
		)
		(fp_line
			(start -0.120396 0.3048)
			(end -0.120396 0.2794)
			(stroke
				(width 0.1)
				(type default)
			)
			(layer "B.Fab")
		)
		(fp_line
			(start -0.120396 0.2794)
			(end 0.12065 0.2794)
			(stroke
				(width 0.1)
				(type default)
			)
			(layer "B.Fab")
		)
		(fp_line
			(start -0.12065 -0.2794)
			(end -0.12065 -0.3048)
			(stroke
				(width 0.1)
				(type default)
			)
			(layer "B.Fab")
		)
		(fp_line
			(start -0.12065 -0.3048)
			(end -0.67945 -0.3048)
			(stroke
				(width 0.1)
				(type default)
			)
			(layer "B.Fab")
		)
		(fp_line
			(start -0.67945 0.3048)
			(end -0.120396 0.3048)
			(stroke
				(width 0.1)
				(type default)
			)
			(layer "B.Fab")
		)
		(fp_line
			(start -0.67945 -0.3048)
			(end -0.67945 0.3048)
			(stroke
				(width 0.1)
				(type default)
			)
			(layer "B.Fab")
		)
		(pad "1" smd circle
			(at 0.40005 0)
			(size 0 0)
			(layers "B.Cu" "B.Mask" "B.Paste")
			(net "JTAG_DBP_BOOT_HALT_N")
		)
		(pad "2" smd circle
			(at -0.40005 0)
			(size 0 0)
			(layers "B.Cu" "B.Mask" "B.Paste")
			(net "FM_ADR_MODE0")
		)
	)
	(footprint ""
		(layer "B.Cu")
		(at 391.416032 -340.08568)
		(property "Reference" "C1398"
			(at 0 0 0)
			(layer "B.SilkS")
			(hide yes)
			(effects
				(font
					(size 1.27 1.27)
				)
				(justify mirror)
			)
		)
		(property "Value" ""
			(at 0 0 0)
			(layer "B.Fab")
			(effects
				(font
					(size 1.27 1.27)
				)
				(justify mirror)
			)
		)
		(duplicate_pad_numbers_are_jumpers no)
		(fp_line
			(start -1.524 -0.762)
			(end -1.524 0.762)
			(stroke
				(width 0.1524)
				(type default)
			)
			(layer "B.SilkS")
		)
		(fp_line
			(start -1.524 0.762)
			(end 1.524 0.762)
			(stroke
				(width 0.1524)
				(type default)
			)
			(layer "B.SilkS")
		)
		(fp_line
			(start 1.524 -0.762)
			(end -1.524 -0.762)
			(stroke
				(width 0.1524)
				(type default)
			)
			(layer "B.SilkS")
		)
		(fp_line
			(start 1.524 0.762)
			(end 1.524 -0.762)
			(stroke
				(width 0.1524)
				(type default)
			)
			(layer "B.SilkS")
		)
		(fp_line
			(start -1.1049 -0.724916)
			(end 1.1049 -0.724916)
			(stroke
				(width 0.1)
				(type default)
			)
			(layer "B.Fab")
		)
		(fp_line
			(start -1.1049 0.724916)
			(end -1.1049 -0.724916)
			(stroke
				(width 0.1)
				(type default)
			)
			(layer "B.Fab")
		)
		(fp_line
			(start 1.1049 -0.724916)
			(end 1.1049 0.724916)
			(stroke
				(width 0.1)
				(type default)
			)
			(layer "B.Fab")
		)
		(fp_line
			(start 1.1049 0.724916)
			(end -1.1049 0.724916)
			(stroke
				(width 0.1)
				(type default)
			)
			(layer "B.Fab")
		)
		(pad "1" smd rect
			(at 0.889 0)
			(size 1.016 1.27)
			(layers "B.Cu" "B.Mask" "B.Paste")
			(net "PVPP_HBM_CPU0")
		)
		(pad "2" smd rect
			(at -0.889 0)
			(size 1.016 1.27)
			(layers "B.Cu" "B.Mask" "B.Paste")
			(net "GND")
		)
	)
	(footprint ""
		(layer "B.Cu")
		(at 449.723764 -76.697586 90)
		(property "Reference" "C2541"
			(at 0 0 90)
			(layer "B.SilkS")
			(hide yes)
			(effects
				(font
					(size 1.27 1.27)
				)
				(justify mirror)
			)
		)
		(property "Value" ""
			(at 0 0 90)
			(layer "B.Fab")
			(effects
				(font
					(size 1.27 1.27)
				)
				(justify mirror)
			)
		)
		(duplicate_pad_numbers_are_jumpers no)
		(fp_line
			(start 0.7874 -0.4064)
			(end -0.7874 -0.4064)
			(stroke
				(width 0.1524)
				(type default)
			)
			(layer "B.SilkS")
		)
		(fp_line
			(start -0.7874 -0.4064)
			(end -0.7874 0.4064)
			(stroke
				(width 0.1524)
				(type default)
			)
			(layer "B.SilkS")
		)
		(fp_line
			(start 0.7874 0.4064)
			(end 0.7874 -0.4064)
			(stroke
				(width 0.1524)
				(type default)
			)
			(layer "B.SilkS")
		)
		(fp_line
			(start -0.7874 0.4064)
			(end 0.7874 0.4064)
			(stroke
				(width 0.1524)
				(type default)
			)
			(layer "B.SilkS")
		)
		(fp_line
			(start 0.67945 -0.305054)
			(end 0.12065 -0.305054)
			(stroke
				(width 0.1)
				(type default)
			)
			(layer "B.Fab")
		)
		(fp_line
			(start 0.12065 -0.305054)
			(end 0.12065 -0.2794)
			(stroke
				(width 0.1)
				(type default)
			)
			(layer "B.Fab")
		)
		(fp_line
			(start -0.12065 -0.3048)
			(end -0.67945 -0.3048)
			(stroke
				(width 0.1)
				(type default)
			)
			(layer "B.Fab")
		)
		(fp_line
			(start -0.67945 -0.3048)
			(end -0.67945 0.3048)
			(stroke
				(width 0.1)
				(type default)
			)
			(layer "B.Fab")
		)
		(fp_line
			(start 0.12065 -0.2794)
			(end -0.12065 -0.2794)
			(stroke
				(width 0.1)
				(type default)
			)
			(layer "B.Fab")
		)
		(fp_line
			(start -0.12065 -0.2794)
			(end -0.12065 -0.3048)
			(stroke
				(width 0.1)
				(type default)
			)
			(layer "B.Fab")
		)
		(fp_line
			(start 0.12065 0.2794)
			(end 0.12065 0.3048)
			(stroke
				(width 0.1)
				(type default)
			)
			(layer "B.Fab")
		)
		(fp_line
			(start -0.120396 0.2794)
			(end 0.12065 0.2794)
			(stroke
				(width 0.1)
				(type default)
			)
			(layer "B.Fab")
		)
		(fp_line
			(start 0.67945 0.3048)
			(end 0.67945 -0.305054)
			(stroke
				(width 0.1)
				(type default)
			)
			(layer "B.Fab")
		)
		(fp_line
			(start 0.12065 0.3048)
			(end 0.67945 0.3048)
			(stroke
				(width 0.1)
				(type default)
			)
			(layer "B.Fab")
		)
		(fp_line
			(start -0.120396 0.3048)
			(end -0.120396 0.2794)
			(stroke
				(width 0.1)
				(type default)
			)
			(layer "B.Fab")
		)
		(fp_line
			(start -0.67945 0.3048)
			(end -0.120396 0.3048)
			(stroke
				(width 0.1)
				(type default)
			)
			(layer "B.Fab")
		)
		(pad "1" smd circle
			(at 0.40005 0 270)
			(size 0 0)
			(layers "B.Cu" "B.Mask" "B.Paste")
			(net "P3V3_AUX_EN")
		)
		(pad "2" smd circle
			(at -0.40005 0 270)
			(size 0 0)
			(layers "B.Cu" "B.Mask" "B.Paste")
			(net "GND")
		)
	)
)
